# S9S_MB_2U (Grand Teton) — schematic netlist excerpt (pin names and nets, part order shuffled) for the footprints in the layout excerpt that follows; sources: Cadence DE-HDL packaged netlist, KiCad conversion of 03242023_DA0F0TMBIJ0_F0T_Motherboard_J_brd_V01_OCP.brd

PC581  Q_CAP  4.7UF 16V 10% X6S  pkg C0603  page 259 : A = P3V3_AUX_VDRV ; B = GND
PC2196  Q_CAP  0.22UF 16V 10% X7R  pkg 0402  page 193 : A = P12V_E1S_TIMER_0 ; B = GND

(kicad_pcb
	(version 20260206)
	(generator "pcbnew")
	(generator_version "10.0")
	(general
		(thickness 1.6)
		(legacy_teardrops no)
	)
	(paper "A4")
	(title_block
		(title "03242023_DA0F0TMBIJ0_F0T_Motherboard_J_brd_V01_OCP.brd")
		(comment 1 "Grand Teton / footprints 3619-3620 of 6105")
	)
	(layers
		(0 "F.Cu" signal "TOP")
		(4 "In1.Cu" signal "GND")
		(6 "In2.Cu" signal "IN1")
		(8 "In3.Cu" signal "GND1")
		(10 "In4.Cu" signal "IN2")
		(12 "In5.Cu" signal "GND2")
		(14 "In6.Cu" signal "IN3")
		(16 "In7.Cu" signal "GND3")
		(18 "In8.Cu" signal "VCC")
		(20 "In9.Cu" signal "VCC1")
		(22 "In10.Cu" signal "GND4")
		(24 "In11.Cu" signal "IN4")
		(26 "In12.Cu" signal "GND5")
		(28 "In13.Cu" signal "IN5")
		(30 "In14.Cu" signal "GND6")
		(32 "In15.Cu" signal "IN6")
		(34 "In16.Cu" signal "GND7")
		(2 "B.Cu" signal "BOTTOM")
		(9 "F.Adhes" user "F.Adhesive")
		(11 "B.Adhes" user "B.Adhesive")
		(13 "F.Paste" user "Package Geometry/Pastemask Top")
		(15 "B.Paste" user "Package Geometry/Pastemask Bottom")
		(5 "F.SilkS" user "Ref Des/Silkscreen Top")
		(7 "B.SilkS" user "Ref Des/Silkscreen Bottom")
		(1 "F.Mask" user "Board Geometry/Soldermask Top")
		(3 "B.Mask" user "Board Geometry/Soldermask Bottom")
		(17 "Dwgs.User" user "User.Drawings")
		(19 "Cmts.User" user "User.Comments")
		(21 "Eco1.User" user "User.Eco1")
		(23 "Eco2.User" user "User.Eco2")
		(25 "Edge.Cuts" user "Board Geometry/Outline")
		(27 "Margin" user)
		(31 "F.CrtYd" user "Package Geometry/Place Bound Top")
		(29 "B.CrtYd" user "Package Geometry/Place Bound Bottom")
		(35 "F.Fab" user "Ref Des/Assembly Top")
		(33 "B.Fab" user "Ref Des/Assembly Bottom")
	)
	(footprint ""
		(layer "F.Cu")
		(at 258.375658 -49.558956)
		(property "Reference" "PC2196"
			(at 0 0 0)
			(layer "F.SilkS")
			(hide yes)
			(effects
				(font
					(size 1.27 1.27)
				)
			)
		)
		(property "Value" ""
			(at 0 0 0)
			(layer "F.Fab")
			(effects
				(font
					(size 1.27 1.27)
				)
			)
		)
		(duplicate_pad_numbers_are_jumpers no)
		(fp_line
			(start -0.7874 -0.4064)
			(end 0.7874 -0.4064)
			(stroke
				(width 0.1524)
				(type default)
			)
			(layer "F.SilkS")
		)
		(fp_line
			(start -0.7874 0.4064)
			(end -0.7874 -0.4064)
			(stroke
				(width 0.1524)
				(type default)
			)
			(layer "F.SilkS")
		)
		(fp_line
			(start 0.7874 -0.4064)
			(end 0.7874 0.4064)
			(stroke
				(width 0.1524)
				(type default)
			)
			(layer "F.SilkS")
		)
		(fp_line
			(start 0.7874 0.4064)
			(end -0.7874 0.4064)
			(stroke
				(width 0.1524)
				(type default)
			)
			(layer "F.SilkS")
		)
		(fp_line
			(start -0.67945 -0.305054)
			(end -0.12065 -0.305054)
			(stroke
				(width 0.1)
				(type default)
			)
			(layer "F.Fab")
		)
		(fp_line
			(start -0.67945 0.3048)
			(end -0.67945 -0.305054)
			(stroke
				(width 0.1)
				(type default)
			)
			(layer "F.Fab")
		)
		(fp_line
			(start -0.12065 -0.305054)
			(end -0.12065 -0.2794)
			(stroke
				(width 0.1)
				(type default)
			)
			(layer "F.Fab")
		)
		(fp_line
			(start -0.12065 -0.2794)
			(end 0.12065 -0.2794)
			(stroke
				(width 0.1)
				(type default)
			)
			(layer "F.Fab")
		)
		(fp_line
			(start -0.12065 0.2794)
			(end -0.12065 0.3048)
			(stroke
				(width 0.1)
				(type default)
			)
			(layer "F.Fab")
		)
		(fp_line
			(start -0.12065 0.3048)
			(end -0.67945 0.3048)
			(stroke
				(width 0.1)
				(type default)
			)
			(layer "F.Fab")
		)
		(fp_line
			(start 0.120396 0.2794)
			(end -0.12065 0.2794)
			(stroke
				(width 0.1)
				(type default)
			)
			(layer "F.Fab")
		)
		(fp_line
			(start 0.120396 0.3048)
			(end 0.120396 0.2794)
			(stroke
				(width 0.1)
				(type default)
			)
			(layer "F.Fab")
		)
		(fp_line
			(start 0.12065 -0.3048)
			(end 0.67945 -0.3048)
			(stroke
				(width 0.1)
				(type default)
			)
			(layer "F.Fab")
		)
		(fp_line
			(start 0.12065 -0.2794)
			(end 0.12065 -0.3048)
			(stroke
				(width 0.1)
				(type default)
			)
			(layer "F.Fab")
		)
		(fp_line
			(start 0.67945 -0.3048)
			(end 0.67945 0.3048)
			(stroke
				(width 0.1)
				(type default)
			)
			(layer "F.Fab")
		)
		(fp_line
			(start 0.67945 0.3048)
			(end 0.120396 0.3048)
			(stroke
				(width 0.1)
				(type default)
			)
			(layer "F.Fab")
		)
		(pad "1" smd circle
			(at -0.40005 0)
			(size 0 0)
			(layers "F.Cu" "F.Mask" "F.Paste")
			(net "P12V_E1S_TIMER_0")
		)
		(pad "2" smd circle
			(at 0.40005 0)
			(size 0 0)
			(layers "F.Cu" "F.Mask" "F.Paste")
			(net "GND")
		)
	)
	(footprint ""
		(layer "F.Cu")
		(at 444.715138 -71.898002 -90)
		(property "Reference" "PC581"
			(at 0 0 270)
			(layer "F.SilkS")
			(hide yes)
			(effects
				(font
					(size 1.27 1.27)
				)
			)
		)
		(property "Value" ""
			(at 0 0 270)
			(layer "F.Fab")
			(effects
				(font
					(size 1.27 1.27)
				)
			)
		)
		(duplicate_pad_numbers_are_jumpers no)
		(fp_line
			(start -1.2954 0.5842)
			(end -1.2954 -0.5842)
			(stroke
				(width 0.1524)
				(type default)
			)
			(layer "F.SilkS")
		)
		(fp_line
			(start 1.2954 0.5842)
			(end -1.2954 0.5842)
			(stroke
				(width 0.1524)
				(type default)
			)
			(layer "F.SilkS")
		)
		(fp_line
			(start -1.2954 -0.5842)
			(end 1.2954 -0.5842)
			(stroke
				(width 0.1524)
				(type default)
			)
			(layer "F.SilkS")
		)
		(fp_line
			(start 0 -0.5842)
			(end 0 0.5842)
			(stroke
				(width 0.1524)
				(type default)
			)
			(layer "F.SilkS")
		)
		(fp_line
			(start 1.2954 -0.5842)
			(end 1.2954 0.5842)
			(stroke
				(width 0.1524)
				(type default)
			)
			(layer "F.SilkS")
		)
		(fp_line
			(start -0.8636 0.4572)
			(end -0.8636 0.4064)
			(stroke
				(width 0.1)
				(type default)
			)
			(layer "F.Fab")
		)
		(fp_line
			(start 0.8636 0.4572)
			(end -0.8636 0.4572)
			(stroke
				(width 0.1)
				(type default)
			)
			(layer "F.Fab")
		)
		(fp_line
			(start -1.1938 0.4064)
			(end -1.1938 -0.4064)
			(stroke
				(width 0.1)
				(type default)
			)
			(layer "F.Fab")
		)
		(fp_line
			(start -0.8636 0.4064)
			(end -1.1938 0.4064)
			(stroke
				(width 0.1)
				(type default)
			)
			(layer "F.Fab")
		)
		(fp_line
			(start 0.8636 0.4064)
			(end 0.8636 0.4572)
			(stroke
				(width 0.1)
				(type default)
			)
			(layer "F.Fab")
		)
		(fp_line
			(start 1.1938 0.4064)
			(end 0.8636 0.4064)
			(stroke
				(width 0.1)
				(type default)
			)
			(layer "F.Fab")
		)
		(fp_line
			(start -1.1938 -0.4064)
			(end -0.8636 -0.4064)
			(stroke
				(width 0.1)
				(type default)
			)
			(layer "F.Fab")
		)
		(fp_line
			(start -0.8636 -0.4064)
			(end -0.8636 -0.4572)
			(stroke
				(width 0.1)
				(type default)
			)
			(layer "F.Fab")
		)
		(fp_line
			(start 0.8636 -0.4064)
			(end 1.1938 -0.4064)
			(stroke
				(width 0.1)
				(type default)
			)
			(layer "F.Fab")
		)
		(fp_line
			(start 1.1938 -0.4064)
			(end 1.1938 0.4064)
			(stroke
				(width 0.1)
				(type default)
			)
			(layer "F.Fab")
		)
		(fp_line
			(start -0.8636 -0.4572)
			(end 0.8636 -0.4572)
			(stroke
				(width 0.1)
				(type default)
			)
			(layer "F.Fab")
		)
		(fp_line
			(start 0.8636 -0.4572)
			(end 0.8636 -0.4064)
			(stroke
				(width 0.1)
				(type default)
			)
			(layer "F.Fab")
		)
		(pad "1" smd rect
			(at -0.7366 0 180)
			(size 0.7112 0.8128)
			(layers "F.Cu" "F.Mask" "F.Paste")
			(net "P3V3_AUX_VDRV")
		)
		(pad "2" smd rect
			(at 0.7366 0 180)
			(size 0.7112 0.8128)
			(layers "F.Cu" "F.Mask" "F.Paste")
			(net "GND")
		)
	)
)
